# BASEBOARD_FAB2 (Tioga Pass) — schematic netlist excerpt (pin names and nets, part order shuffled) for the footprints in the layout excerpt that follows; sources: Cadence DE-HDL packaged netlist, KiCad conversion of Wiwynn_Tioga_Pass_MB.brd

C9N19  CAP  10UF 16V 10% X6S  pkg 0805  page 210 : A = VR_FET_SW_P12V_STBY_PVCCIN_CPU1 ; B = GND
R2L22  RES  1.00K 1% CHIP  pkg 0402  page 173 : A = PD_SATA1_CONTROLLER_TYPE_R ; B = GND
C7U3  CAP  10UF 4V 20% X6S  pkg 0603LF  page 233 : A = PVPP_GHJ ; B = GND

(kicad_pcb
	(version 20260206)
	(generator "pcbnew")
	(generator_version "10.0")
	(general
		(thickness 1.6)
		(legacy_teardrops no)
	)
	(paper "A4")
	(title_block
		(title "Wiwynn_Tioga_Pass_MB.brd")
		(comment 1 "Tioga Pass / footprints 4154-4156 of 4770")
	)
	(layers
		(0 "F.Cu" signal "TOP")
		(4 "In1.Cu" signal "L2GND")
		(6 "In2.Cu" signal "L3")
		(8 "In3.Cu" signal "L4GND")
		(10 "In4.Cu" signal "L5")
		(12 "In5.Cu" signal "L6GND")
		(14 "In6.Cu" signal "L7VCC")
		(16 "In7.Cu" signal "L8VCC")
		(18 "In8.Cu" signal "L9GND")
		(20 "In9.Cu" signal "L10")
		(22 "In10.Cu" signal "L11GND")
		(24 "In11.Cu" signal "L12")
		(26 "In12.Cu" signal "L13GND")
		(2 "B.Cu" signal "BOTTOM")
		(9 "F.Adhes" user "F.Adhesive")
		(11 "B.Adhes" user "B.Adhesive")
		(13 "F.Paste" user "Package Geometry/Pastemask Top")
		(15 "B.Paste" user "Package Geometry/Pastemask Bottom")
		(5 "F.SilkS" user "Ref Des/Silkscreen Top")
		(7 "B.SilkS" user "Ref Des/Silkscreen Bottom")
		(1 "F.Mask" user "Board Geometry/Soldermask Top")
		(3 "B.Mask" user "Board Geometry/Soldermask Bottom")
		(17 "Dwgs.User" user "User.Drawings")
		(19 "Cmts.User" user "User.Comments")
		(21 "Eco1.User" user "User.Eco1")
		(23 "Eco2.User" user "User.Eco2")
		(25 "Edge.Cuts" user "Board Geometry/Outline")
		(27 "Margin" user)
		(31 "F.CrtYd" user "Package Geometry/Place Bound Top")
		(29 "B.CrtYd" user "Package Geometry/Place Bound Bottom")
		(35 "F.Fab" user "Ref Des/Assembly Top")
		(33 "B.Fab" user "Ref Des/Assembly Bottom")
	)
	(footprint ""
		(layer "B.Cu")
		(at 155.194 -8.128 90)
		(property "Reference" "C7U3"
			(at 0 0 90)
			(layer "B.SilkS")
			(hide yes)
			(effects
				(font
					(size 1.27 1.27)
				)
				(justify mirror)
			)
		)
		(property "Value" ""
			(at 0 0 90)
			(layer "B.Fab")
			(effects
				(font
					(size 1.27 1.27)
				)
				(justify mirror)
			)
		)
		(duplicate_pad_numbers_are_jumpers no)
		(fp_poly
			(pts
				(xy 0.4953 -0.2032) (xy -0.4953 -0.2032) (xy -0.4953 1.6002) (xy 0.4953 1.6002)
			)
			(stroke
				(width 0)
				(type default)
			)
			(fill no)
			(layer "B.CrtYd")
		)
		(fp_line
			(start 0.4953 -0.2032)
			(end -0.4953 -0.2032)
			(stroke
				(width 0.1)
				(type default)
			)
			(layer "B.Fab")
		)
		(fp_line
			(start -0.4953 -0.2032)
			(end -0.4953 1.6002)
			(stroke
				(width 0.1)
				(type default)
			)
			(layer "B.Fab")
		)
		(fp_line
			(start 0.4953 1.6002)
			(end 0.4953 -0.2032)
			(stroke
				(width 0.1)
				(type default)
			)
			(layer "B.Fab")
		)
		(fp_line
			(start -0.4953 1.6002)
			(end 0.4953 1.6002)
			(stroke
				(width 0.1)
				(type default)
			)
			(layer "B.Fab")
		)
		(pad "1" smd rect
			(at 0 0 270)
			(size 0.762 0.889)
			(layers "B.Cu" "B.Mask" "B.Paste")
			(net "PVPP_GHJ")
		)
		(pad "2" smd rect
			(at 0 1.397 270)
			(size 0.762 0.889)
			(layers "B.Cu" "B.Mask" "B.Paste")
			(net "GND")
		)
		(zone
			(layer "B.Cu")
			(hatch none 0.5)
			(connect_pads
				(clearance 0)
			)
			(min_thickness 0.25)
			(keepout
				(tracks not_allowed)
				(vias allowed)
				(pads allowed)
				(copperpour not_allowed)
				(footprints allowed)
			)
			(placement
				(enabled no)
				(sheetname "")
			)
			(fill
				(thermal_gap 0.5)
				(thermal_bridge_width 0.5)
				(island_removal_mode 0)
			)
			(polygon
				(pts
					(xy 155.6385 -8.509) (xy 155.6385 -7.747) (xy 156.1465 -7.747) (xy 156.1465 -8.509)
				)
			)
		)
	)
	(footprint ""
		(layer "B.Cu")
		(at 32.832802 -98.937064 90)
		(property "Reference" "C9N19"
			(at 0 0 90)
			(layer "B.SilkS")
			(hide yes)
			(effects
				(font
					(size 1.27 1.27)
				)
				(justify mirror)
			)
		)
		(property "Value" ""
			(at 0 0 90)
			(layer "B.Fab")
			(effects
				(font
					(size 1.27 1.27)
				)
				(justify mirror)
			)
		)
		(duplicate_pad_numbers_are_jumpers no)
		(fp_poly
			(pts
				(xy 0.7239 -0.2159) (xy -0.7239 -0.2159) (xy -0.7239 1.9939) (xy 0.7239 1.9939)
			)
			(stroke
				(width 0)
				(type default)
			)
			(fill no)
			(layer "B.CrtYd")
		)
		(fp_line
			(start 0.7239 -0.2159)
			(end 0.7239 1.9939)
			(stroke
				(width 0.1)
				(type default)
			)
			(layer "B.Fab")
		)
		(fp_line
			(start -0.7239 -0.2159)
			(end 0.7239 -0.2159)
			(stroke
				(width 0.1)
				(type default)
			)
			(layer "B.Fab")
		)
		(fp_line
			(start 0.7239 1.9939)
			(end -0.7239 1.9939)
			(stroke
				(width 0.1)
				(type default)
			)
			(layer "B.Fab")
		)
		(fp_line
			(start -0.7239 1.9939)
			(end -0.7239 -0.2159)
			(stroke
				(width 0.1)
				(type default)
			)
			(layer "B.Fab")
		)
		(pad "1" smd rect
			(at 0 0 270)
			(size 1.27 1.016)
			(layers "B.Cu" "B.Mask" "B.Paste")
			(net "VR_FET_SW_P12V_STBY_PVCCIN_CPU1")
		)
		(pad "2" smd rect
			(at 0 1.778 270)
			(size 1.27 1.016)
			(layers "B.Cu" "B.Mask" "B.Paste")
			(net "GND")
		)
		(zone
			(layer "B.Cu")
			(hatch none 0.5)
			(connect_pads
				(clearance 0)
			)
			(min_thickness 0.25)
			(keepout
				(tracks not_allowed)
				(vias allowed)
				(pads allowed)
				(copperpour not_allowed)
				(footprints allowed)
			)
			(placement
				(enabled no)
				(sheetname "")
			)
			(fill
				(thermal_gap 0.5)
				(thermal_bridge_width 0.5)
				(island_removal_mode 0)
			)
			(polygon
				(pts
					(xy 33.340802 -99.572064) (xy 33.340802 -98.302064) (xy 34.102802 -98.302064) (xy 34.102802 -99.572064)
				)
			)
		)
	)
	(footprint ""
		(layer "B.Cu")
		(at 417.006024 -141.732)
		(property "Reference" "R2L22"
			(at 0 0 0)
			(layer "B.SilkS")
			(hide yes)
			(effects
				(font
					(size 1.27 1.27)
				)
				(justify mirror)
			)
		)
		(property "Value" ""
			(at 0 0 0)
			(layer "B.Fab")
			(effects
				(font
					(size 1.27 1.27)
				)
				(justify mirror)
			)
		)
		(duplicate_pad_numbers_are_jumpers no)
		(fp_poly
			(pts
				(xy 0.2794 -0.1016) (xy -0.2794 -0.1016) (xy -0.2794 0.9906) (xy 0.2794 0.9906)
			)
			(stroke
				(width 0)
				(type default)
			)
			(fill no)
			(layer "B.CrtYd")
		)
		(fp_line
			(start -0.2794 -0.1016)
			(end 0.2794 -0.1016)
			(stroke
				(width 0.1)
				(type default)
			)
			(layer "B.Fab")
		)
		(fp_line
			(start -0.2794 0.9906)
			(end -0.2794 -0.1016)
			(stroke
				(width 0.1)
				(type default)
			)
			(layer "B.Fab")
		)
		(fp_line
			(start 0.2794 -0.1016)
			(end 0.2794 0.9906)
			(stroke
				(width 0.1)
				(type default)
			)
			(layer "B.Fab")
		)
		(fp_line
			(start 0.2794 0.9906)
			(end -0.2794 0.9906)
			(stroke
				(width 0.1)
				(type default)
			)
			(layer "B.Fab")
		)
		(pad "1" smd rect
			(at 0 0 180)
			(size 0.508 0.508)
			(layers "B.Cu" "B.Mask" "B.Paste")
			(net "PD_SATA1_CONTROLLER_TYPE_R")
		)
		(pad "2" smd rect
			(at 0 0.889 180)
			(size 0.508 0.508)
			(layers "B.Cu" "B.Mask" "B.Paste")
			(net "GND")
		)
		(zone
			(layer "B.Cu")
			(hatch none 0.5)
			(connect_pads
				(clearance 0)
			)
			(min_thickness 0.25)
			(keepout
				(tracks allowed)
				(vias not_allowed)
				(pads allowed)
				(copperpour not_allowed)
				(footprints allowed)
			)
			(placement
				(enabled no)
				(sheetname "")
			)
			(fill
				(thermal_gap 0.5)
				(thermal_bridge_width 0.5)
				(island_removal_mode 0)
			)
			(polygon
				(pts
					(xy 417.260024 -141.478) (xy 416.752024 -141.478) (xy 416.752024 -141.097) (xy 417.260024 -141.097)
				)
			)
		)
		(zone
			(layer "B.Cu")
			(hatch none 0.5)
			(connect_pads
				(clearance 0)
			)
			(min_thickness 0.25)
			(keepout
				(tracks not_allowed)
				(vias allowed)
				(pads allowed)
				(copperpour not_allowed)
				(footprints allowed)
			)
			(placement
				(enabled no)
				(sheetname "")
			)
			(fill
				(thermal_gap 0.5)
				(thermal_bridge_width 0.5)
				(island_removal_mode 0)
			)
			(polygon
				(pts
					(xy 417.260024 -141.097) (xy 416.752024 -141.097) (xy 416.752024 -141.478) (xy 417.260024 -141.478)
				)
			)
		)
	)
)
